# T6G (Grand Teton) — schematic netlist excerpt (pin names and nets, part order shuffled) for the footprints in the layout excerpt that follows; sources: Cadence DE-HDL packaged netlist, KiCad conversion of 04192023_DAF0TMB3IC0_F0TG_MB_C_brd_V02_OCP.brd

R6046  Q_RES  100 1% CHIP  pkg 0402LF  page 81 : A = HP_LVC3_OCP_SFF_PRSNT2_PLD_N ; B = PRSNT_OCP_SFF_N

Q54  MOSFET_NCH_GDS_ESD_PROTECTED  2N7002K IC  pkg SOT23_GDSXC  page 242
  D  = P12V_AUX_BLEEDING
  G  = FM_P12V_HSC_EN_R_N
  S  = GND

(kicad_pcb
	(version 20260206)
	(generator "pcbnew")
	(generator_version "10.0")
	(general
		(thickness 1.6)
		(legacy_teardrops no)
	)
	(paper "A4")
	(title_block
		(title "04192023_DAF0TMB3IC0_F0TG_MB_C_brd_V02_OCP.brd")
		(comment 1 "Grand Teton / footprints 2984-2985 of 8354")
	)
	(layers
		(0 "F.Cu" signal "TOP")
		(4 "In1.Cu" signal "GND")
		(6 "In2.Cu" signal "IN1")
		(8 "In3.Cu" signal "GND1")
		(10 "In4.Cu" signal "IN2")
		(12 "In5.Cu" signal "GND2")
		(14 "In6.Cu" signal "IN3")
		(16 "In7.Cu" signal "GND3")
		(18 "In8.Cu" signal "VCC")
		(20 "In9.Cu" signal "VCC1")
		(22 "In10.Cu" signal "GND4")
		(24 "In11.Cu" signal "IN4")
		(26 "In12.Cu" signal "GND5")
		(28 "In13.Cu" signal "IN5")
		(30 "In14.Cu" signal "GND6")
		(32 "In15.Cu" signal "IN6")
		(34 "In16.Cu" signal "GND7")
		(2 "B.Cu" signal "BOTTOM")
		(9 "F.Adhes" user "F.Adhesive")
		(11 "B.Adhes" user "B.Adhesive")
		(13 "F.Paste" user "Package Geometry/Pastemask Top")
		(15 "B.Paste" user "Package Geometry/Pastemask Bottom")
		(5 "F.SilkS" user "Ref Des/Silkscreen Top")
		(7 "B.SilkS" user "Ref Des/Silkscreen Bottom")
		(1 "F.Mask" user "Board Geometry/Soldermask Top")
		(3 "B.Mask" user "Board Geometry/Soldermask Bottom")
		(17 "Dwgs.User" user "User.Drawings")
		(19 "Cmts.User" user "User.Comments")
		(21 "Eco1.User" user "User.Eco1")
		(23 "Eco2.User" user "User.Eco2")
		(25 "Edge.Cuts" user "Board Geometry/Outline")
		(27 "Margin" user)
		(31 "F.CrtYd" user "Package Geometry/Place Bound Top")
		(29 "B.CrtYd" user "Package Geometry/Place Bound Bottom")
		(35 "F.Fab" user "Ref Des/Assembly Top")
		(33 "B.Fab" user "Ref Des/Assembly Bottom")
	)
	(footprint ""
		(layer "F.Cu")
		(at 209.622136 -142.582138)
		(property "Reference" "Q54"
			(at -1.651 -2.25933 0)
			(unlocked yes)
			(layer "F.SilkS")
			(effects
				(font
					(size 0.7874 0.5842)
					(thickness 0.1524)
				)
				(justify left)
			)
		)
		(property "Value" ""
			(at 0 0 0)
			(layer "F.Fab")
			(effects
				(font
					(size 1.27 1.27)
				)
			)
		)
		(duplicate_pad_numbers_are_jumpers no)
		(fp_line
			(start -1.603248 -1.500124)
			(end 1.603248 -1.500124)
			(stroke
				(width 0.1524)
				(type default)
			)
			(layer "F.SilkS")
		)
		(fp_line
			(start -1.603248 1.500124)
			(end -1.603248 -1.500124)
			(stroke
				(width 0.1524)
				(type default)
			)
			(layer "F.SilkS")
		)
		(fp_line
			(start 1.603248 -1.500124)
			(end 1.603248 1.500124)
			(stroke
				(width 0.1524)
				(type default)
			)
			(layer "F.SilkS")
		)
		(fp_line
			(start 1.603248 1.500124)
			(end -1.603248 1.500124)
			(stroke
				(width 0.1524)
				(type default)
			)
			(layer "F.SilkS")
		)
		(fp_line
			(start -1.249934 -1.169924)
			(end -1.249934 -0.729996)
			(stroke
				(width 0.1)
				(type default)
			)
			(layer "F.Fab")
		)
		(fp_line
			(start -1.249934 -0.729996)
			(end -0.6985 -0.729996)
			(stroke
				(width 0.1)
				(type default)
			)
			(layer "F.Fab")
		)
		(fp_line
			(start -1.249934 0.729996)
			(end -1.249934 1.169924)
			(stroke
				(width 0.1)
				(type default)
			)
			(layer "F.Fab")
		)
		(fp_line
			(start -1.249934 1.169924)
			(end -0.700024 1.169924)
			(stroke
				(width 0.1)
				(type default)
			)
			(layer "F.Fab")
		)
		(fp_line
			(start -0.700024 -1.500124)
			(end -0.700024 -1.169924)
			(stroke
				(width 0.1)
				(type default)
			)
			(layer "F.Fab")
		)
		(fp_line
			(start -0.700024 -1.169924)
			(end -1.249934 -1.169924)
			(stroke
				(width 0.1)
				(type default)
			)
			(layer "F.Fab")
		)
		(fp_line
			(start -0.700024 1.169924)
			(end -0.700024 1.500124)
			(stroke
				(width 0.1)
				(type default)
			)
			(layer "F.Fab")
		)
		(fp_line
			(start -0.700024 1.500124)
			(end 0.700024 1.500124)
			(stroke
				(width 0.1)
				(type default)
			)
			(layer "F.Fab")
		)
		(fp_line
			(start -0.6985 -0.729996)
			(end -0.6985 0.729996)
			(stroke
				(width 0.1)
				(type default)
			)
			(layer "F.Fab")
		)
		(fp_line
			(start -0.6985 0.729996)
			(end -1.249934 0.729996)
			(stroke
				(width 0.1)
				(type default)
			)
			(layer "F.Fab")
		)
		(fp_line
			(start 0.700024 -1.500124)
			(end -0.700024 -1.500124)
			(stroke
				(width 0.1)
				(type default)
			)
			(layer "F.Fab")
		)
		(fp_line
			(start 0.700024 -0.219964)
			(end 0.700024 -1.500124)
			(stroke
				(width 0.1)
				(type default)
			)
			(layer "F.Fab")
		)
		(fp_line
			(start 0.700024 0.219964)
			(end 1.249934 0.219964)
			(stroke
				(width 0.1)
				(type default)
			)
			(layer "F.Fab")
		)
		(fp_line
			(start 0.700024 1.500124)
			(end 0.700024 0.219964)
			(stroke
				(width 0.1)
				(type default)
			)
			(layer "F.Fab")
		)
		(fp_line
			(start 1.249934 -0.219964)
			(end 0.700024 -0.219964)
			(stroke
				(width 0.1)
				(type default)
			)
			(layer "F.Fab")
		)
		(fp_line
			(start 1.249934 0.219964)
			(end 1.249934 -0.219964)
			(stroke
				(width 0.1)
				(type default)
			)
			(layer "F.Fab")
		)
		(fp_rect
			(start -0.700024 1.500124)
			(end 0.700024 -1.500124)
			(stroke
				(width 0)
				(type default)
			)
			(fill no)
			(layer "F.Fab")
		)
		(pad "D" smd rect
			(at 0.999998 0 270)
			(size 0.8128 0.9144)
			(layers "F.Cu" "F.Mask" "F.Paste")
			(net "P12V_AUX_BLEEDING")
		)
		(pad "G" smd rect
			(at -0.999998 -0.94996 270)
			(size 0.8128 0.9144)
			(layers "F.Cu" "F.Mask" "F.Paste")
			(net "FM_P12V_HSC_EN_R_N")
		)
		(pad "S" smd rect
			(at -0.999998 0.94996 270)
			(size 0.8128 0.9144)
			(layers "F.Cu" "F.Mask" "F.Paste")
			(net "GND")
		)
	)
	(footprint ""
		(layer "F.Cu")
		(at 208.894426 -108.545376 180)
		(property "Reference" "R6046"
			(at 0 0 180)
			(layer "F.SilkS")
			(hide yes)
			(effects
				(font
					(size 1.27 1.27)
				)
			)
		)
		(property "Value" ""
			(at 0 0 180)
			(layer "F.Fab")
			(effects
				(font
					(size 1.27 1.27)
				)
			)
		)
		(duplicate_pad_numbers_are_jumpers no)
		(fp_line
			(start 0.7874 0.4064)
			(end -0.7874 0.4064)
			(stroke
				(width 0.1524)
				(type default)
			)
			(layer "F.SilkS")
		)
		(fp_line
			(start 0.7874 -0.4064)
			(end 0.7874 0.4064)
			(stroke
				(width 0.1524)
				(type default)
			)
			(layer "F.SilkS")
		)
		(fp_line
			(start -0.7874 0.4064)
			(end -0.7874 -0.4064)
			(stroke
				(width 0.1524)
				(type default)
			)
			(layer "F.SilkS")
		)
		(fp_line
			(start -0.7874 -0.4064)
			(end 0.7874 -0.4064)
			(stroke
				(width 0.1524)
				(type default)
			)
			(layer "F.SilkS")
		)
		(fp_line
			(start 0.67945 0.3048)
			(end 0.120396 0.3048)
			(stroke
				(width 0.1)
				(type default)
			)
			(layer "F.Fab")
		)
		(fp_line
			(start 0.67945 -0.3048)
			(end 0.67945 0.3048)
			(stroke
				(width 0.1)
				(type default)
			)
			(layer "F.Fab")
		)
		(fp_line
			(start 0.12065 -0.2794)
			(end 0.12065 -0.3048)
			(stroke
				(width 0.1)
				(type default)
			)
			(layer "F.Fab")
		)
		(fp_line
			(start 0.12065 -0.3048)
			(end 0.67945 -0.3048)
			(stroke
				(width 0.1)
				(type default)
			)
			(layer "F.Fab")
		)
		(fp_line
			(start 0.120396 0.3048)
			(end 0.120396 0.2794)
			(stroke
				(width 0.1)
				(type default)
			)
			(layer "F.Fab")
		)
		(fp_line
			(start 0.120396 0.2794)
			(end -0.12065 0.2794)
			(stroke
				(width 0.1)
				(type default)
			)
			(layer "F.Fab")
		)
		(fp_line
			(start -0.12065 0.3048)
			(end -0.67945 0.3048)
			(stroke
				(width 0.1)
				(type default)
			)
			(layer "F.Fab")
		)
		(fp_line
			(start -0.12065 0.2794)
			(end -0.12065 0.3048)
			(stroke
				(width 0.1)
				(type default)
			)
			(layer "F.Fab")
		)
		(fp_line
			(start -0.12065 -0.2794)
			(end 0.12065 -0.2794)
			(stroke
				(width 0.1)
				(type default)
			)
			(layer "F.Fab")
		)
		(fp_line
			(start -0.12065 -0.305054)
			(end -0.12065 -0.2794)
			(stroke
				(width 0.1)
				(type default)
			)
			(layer "F.Fab")
		)
		(fp_line
			(start -0.67945 0.3048)
			(end -0.67945 -0.305054)
			(stroke
				(width 0.1)
				(type default)
			)
			(layer "F.Fab")
		)
		(fp_line
			(start -0.67945 -0.305054)
			(end -0.12065 -0.305054)
			(stroke
				(width 0.1)
				(type default)
			)
			(layer "F.Fab")
		)
		(pad "1" smd circle
			(at -0.40005 0 180)
			(size 0 0)
			(layers "F.Cu" "F.Mask" "F.Paste")
			(net "HP_LVC3_OCP_SFF_PRSNT2_PLD_N")
		)
		(pad "2" smd circle
			(at 0.40005 0 180)
			(size 0 0)
			(layers "F.Cu" "F.Mask" "F.Paste")
			(net "PRSNT_OCP_SFF_N")
		)
	)
)
